FILE_TYPE = MULTI_PHYS_TABLE;
PART 'SWITCH_D90553001'
{======================================================================================================================================================}
:PACK_TYPE | MATERIAL | PART_NUMBER     = EnvComp | PART_NUMBER  | JEDEC_TYPE | DESCRIPTION               | CLASS | HEIGHT     | COMPONENT_TYPE | LPID  | SPEED_URL | Status |RPL| AML | Bus_Unit | Days ;
{======================================================================================================================================================}
'SMLF'     | 'IC'     | 'D90553-001'(!) = 'YES;YES;UNK;UNK;ok;CIP' | 'D90553-001' | 'SSW2RPB'  | 'SW PB SMT TL1015AF160QG' | 'IC'  | '0.083 IN' | 'SMTOTHER'     | '' | 'http://speed.intel.com:8081/speed/module/pdm/item/pdm_item_detail_direct.asp?item_cde=D90553-001&item_rev=01&url_param=unused' | 'Conditional' | 'NO' | '1' | 'SMO_BOARDS' | '???' 
'SMLF'     | 'EMPTY'  | 'D90553-001'(!) = 'YES;YES;UNK;UNK;ok;CIP' | 'D90553-001' | 'SSW2RPB'  | 'SW PB SMT TL1015AF160QG' | 'IO'  | '0.083 IN' | 'SMTOTHER'     | '' | 'http://speed.intel.com:8081/speed/module/pdm/item/pdm_item_detail_direct.asp?item_cde=D90553-001&item_rev=01&url_param=unused' | 'Conditional' | 'NO' | '1' | 'SMO_BOARDS' | '???' 
END_PART
END.
